(kicad_pcb
	(version 20241229)
	(generator "pcbnew")
	(generator_version "9.0")
	(general
		(thickness 1.62)
		(legacy_teardrops no)
	)
	(paper "A4")
	(title_block
		(title "OCuLink to 10GbE adapter")
		(date "2026-02-23")
		(rev "1.1.0")
		(company "Antmicro Ltd")
		(comment 1 "www.antmicro.com")
		(comment 9 "footprints 254-258 of 510")
	)
	(layers
		(0 "F.Cu" signal)
		(4 "In1.Cu" signal)
		(6 "In2.Cu" signal)
		(8 "In3.Cu" signal)
		(10 "In4.Cu" signal)
		(12 "In5.Cu" signal)
		(14 "In6.Cu" signal)
		(2 "B.Cu" signal)
		(9 "F.Adhes" user "F.Adhesive")
		(11 "B.Adhes" user "B.Adhesive")
		(13 "F.Paste" user)
		(15 "B.Paste" user)
		(5 "F.SilkS" user "F.Silkscreen")
		(7 "B.SilkS" user "B.Silkscreen")
		(1 "F.Mask" user)
		(3 "B.Mask" user)
		(17 "Dwgs.User" user "User.Drawings")
		(19 "Cmts.User" user "User.Comments")
		(21 "Eco1.User" user "User.Eco1")
		(23 "Eco2.User" user "User.Eco2")
		(25 "Edge.Cuts" user)
		(27 "Margin" user)
		(31 "F.CrtYd" user "F.Courtyard")
		(29 "B.CrtYd" user "B.Courtyard")
		(35 "F.Fab" user)
		(33 "B.Fab" user)
	)
	(footprint "antmicro-footprints:SOT-23-6"
		(layer "F.Cu")
		(at 70.21 66 180)
		(property "Reference" "U11"
			(at -1.71 0.31 90)
			(layer "F.SilkS")
			(effects
				(font
					(size 0.7 0.7)
					(thickness 0.15)
				)
				(justify right top)
			)
		)
		(property "Value" "LTC4412IS6"
			(at -1.749999 2.693 0)
			(layer "F.Fab")
			(hide yes)
			(effects
				(font
					(size 0.7 0.7)
					(thickness 0.15)
				)
				(justify right top)
			)
		)
		(property "Datasheet" "https://www.analog.com/media/en/technical-documentation/data-sheets/4412fb.pdf"
			(at 0 -0.057 0)
			(layer "F.Fab")
			(hide yes)
			(effects
				(font
					(size 1.27 1.27)
					(thickness 0.15)
				)
			)
		)
		(property "Description" "Ideal diode controller"
			(at 0 -0.057 0)
			(layer "F.Fab")
			(hide yes)
			(effects
				(font
					(size 1.27 1.27)
					(thickness 0.15)
				)
			)
		)
		(property "MPN" "LTC4412IS6#TRMPBF"
			(at 0 0 180)
			(unlocked yes)
			(layer "F.Fab")
			(hide yes)
			(effects
				(font
					(size 1 1)
					(thickness 0.15)
				)
			)
		)
		(property "Manufacturer" "Analog Devices"
			(at 0 0 180)
			(unlocked yes)
			(layer "F.Fab")
			(hide yes)
			(effects
				(font
					(size 1 1)
					(thickness 0.15)
				)
			)
		)
		(property "Author" "Antmicro"
			(at 0 0 180)
			(unlocked yes)
			(layer "F.Fab")
			(hide yes)
			(effects
				(font
					(size 1 1)
					(thickness 0.15)
				)
			)
		)
		(property "License" "Apache-2.0"
			(at 0 0 180)
			(unlocked yes)
			(layer "F.Fab")
			(hide yes)
			(effects
				(font
					(size 1 1)
					(thickness 0.15)
				)
			)
		)
		(sheetname "/Power/Ideal diode 1/")
		(sheetfile "ideal-diode.kicad_sch")
		(attr smd)
		(fp_line
			(start 1.45 0.643)
			(end 1.45 0.343)
			(stroke
				(width 0.12)
				(type solid)
			)
			(layer "F.SilkS")
		)
		(fp_line
			(start 1.45 -0.757)
			(end 1.45 -0.457)
			(stroke
				(width 0.12)
				(type solid)
			)
			(layer "F.SilkS")
		)
		(fp_line
			(start 1.3 0.643)
			(end 1.45 0.643)
			(stroke
				(width 0.12)
				(type solid)
			)
			(layer "F.SilkS")
		)
		(fp_line
			(start 1.3 -0.757)
			(end 1.45 -0.757)
			(stroke
				(width 0.12)
				(type solid)
			)
			(layer "F.SilkS")
		)
		(fp_line
			(start -1.3 -0.757)
			(end -1.45 -0.757)
			(stroke
				(width 0.12)
				(type solid)
			)
			(layer "F.SilkS")
		)
		(fp_line
			(start -1.45 0.643)
			(end -1.45 0.343)
			(stroke
				(width 0.12)
				(type solid)
			)
			(layer "F.SilkS")
		)
		(fp_line
			(start -1.45 -0.757)
			(end -1.45 -0.457)
			(stroke
				(width 0.12)
				(type solid)
			)
			(layer "F.SilkS")
		)
		(fp_rect
			(start -1.55 -1.85)
			(end 1.55 1.75)
			(stroke
				(width 0.05)
				(type solid)
			)
			(fill no)
			(layer "F.CrtYd")
		)
		(fp_line
			(start 1.5 0.643)
			(end -1.5 0.643)
			(stroke
				(width 0.1)
				(type solid)
			)
			(layer "F.Fab")
		)
		(fp_line
			(start 1.5 -0.757)
			(end 1.5 0.643)
			(stroke
				(width 0.1)
				(type solid)
			)
			(layer "F.Fab")
		)
		(fp_line
			(start -1.5 0.643)
			(end -1.5 -0.757)
			(stroke
				(width 0.1)
				(type solid)
			)
			(layer "F.Fab")
		)
		(fp_line
			(start -1.5 -0.757)
			(end 1.5 -0.757)
			(stroke
				(width 0.1)
				(type solid)
			)
			(layer "F.Fab")
		)
		(pad "1" smd roundrect
			(at -0.954 1.1 180)
			(size 0.55 1)
			(layers "F.Cu" "F.Mask" "F.Paste")
			(roundrect_rratio 0.15)
			(net 350 "/Power/+12V_IN")
			(pinfunction "IN")
			(pintype "power_in")
		)
		(pad "2" smd roundrect
			(at -0.003 1.1 180)
			(size 0.55 1)
			(layers "F.Cu" "F.Mask" "F.Paste")
			(roundrect_rratio 0.15)
			(net 28 "GND")
			(pinfunction "GND")
			(pintype "power_in")
		)
		(pad "3" smd roundrect
			(at 0.947 1.1 180)
			(size 0.55 1)
			(layers "F.Cu" "F.Mask" "F.Paste")
			(roundrect_rratio 0.15)
			(net 28 "GND")
			(pinfunction "CTL")
			(pintype "input")
		)
		(pad "4" smd roundrect
			(at 0.947 -1.214 180)
			(size 0.55 1)
			(layers "F.Cu" "F.Mask" "F.Paste")
			(roundrect_rratio 0.15)
			(net 374 "unconnected-(U11-STAT-Pad4)")
			(pinfunction "STAT")
			(pintype "output+no_connect")
		)
		(pad "5" smd roundrect
			(at -0.003 -1.214 180)
			(size 0.55 1)
			(layers "F.Cu" "F.Mask" "F.Paste")
			(roundrect_rratio 0.15)
			(net 373 "Net-(Q2-G)")
			(pinfunction "GATE")
			(pintype "output")
		)
		(pad "6" smd roundrect
			(at -0.954 -1.214 180)
			(size 0.55 1)
			(layers "F.Cu" "F.Mask" "F.Paste")
			(roundrect_rratio 0.15)
			(net 314 "VCC")
			(pinfunction "SENSE")
			(pintype "input")
		)
	)
	(footprint "antmicro-footprints:R_0402_1005Metric"
		(layer "F.Cu")
		(at 101.3 107.1 180)
		(descr "Resistor SMD 0402")
		(tags "resistor SMD 0402")
		(property "Reference" "R81"
			(at 0.8 -15.55 0)
			(layer "F.SilkS")
			(effects
				(font
					(size 0.7 0.7)
					(thickness 0.15)
				)
				(justify left bottom)
			)
		)
		(property "Value" "R_100k_0402"
			(at -1.011843 1.772046 0)
			(layer "F.Fab")
			(hide yes)
			(effects
				(font
					(size 0.7 0.7)
					(thickness 0.15)
				)
				(justify right top)
			)
		)
		(property "Datasheet" "https://www.bourns.com/docs/product-datasheets/cr.pdf"
			(at 0 0 0)
			(layer "F.Fab")
			(hide yes)
			(effects
				(font
					(size 1.27 1.27)
					(thickness 0.15)
				)
			)
		)
		(property "Description" "SMD Chip Resistor, 100 kohm, ± 1%, 62.5 mW, 0402 [1005 Metric], Thick Film, General Purpose"
			(at 0 0 0)
			(layer "F.Fab")
			(hide yes)
			(effects
				(font
					(size 1.27 1.27)
					(thickness 0.15)
				)
			)
		)
		(property "MPN" "CR0402-FX-1003GLF"
			(at 0 0 180)
			(unlocked yes)
			(layer "F.Fab")
			(hide yes)
			(effects
				(font
					(size 1 1)
					(thickness 0.15)
				)
			)
		)
		(property "Manufacturer" "Bourns"
			(at 0 0 180)
			(unlocked yes)
			(layer "F.Fab")
			(hide yes)
			(effects
				(font
					(size 1 1)
					(thickness 0.15)
				)
			)
		)
		(property "License" "Apache-2.0"
			(at 0 0 180)
			(unlocked yes)
			(layer "F.Fab")
			(hide yes)
			(effects
				(font
					(size 1 1)
					(thickness 0.15)
				)
			)
		)
		(property "Author" "Antmicro"
			(at 0 0 180)
			(unlocked yes)
			(layer "F.Fab")
			(hide yes)
			(effects
				(font
					(size 1 1)
					(thickness 0.15)
				)
			)
		)
		(property "Val" "100k"
			(at 0 0 180)
			(unlocked yes)
			(layer "F.Fab")
			(hide yes)
			(effects
				(font
					(size 1 1)
					(thickness 0.15)
				)
			)
		)
		(property "Tolerance" "1%"
			(at 0 0 180)
			(unlocked yes)
			(layer "F.Fab")
			(hide yes)
			(effects
				(font
					(size 1 1)
					(thickness 0.15)
				)
			)
		)
		(sheetname "/X710-AT2 Misc/")
		(sheetfile "x710-at2-mics.kicad_sch")
		(attr smd)
		(fp_rect
			(start -0.925 -0.47)
			(end 0.925 0.47)
			(stroke
				(width 0.05)
				(type default)
			)
			(fill no)
			(layer "F.CrtYd")
		)
		(fp_rect
			(start -0.5 -0.25)
			(end 0.5 0.25)
			(stroke
				(width 0.15)
				(type solid)
			)
			(fill no)
			(layer "F.Fab")
		)
		(pad "1" smd roundrect
			(at -0.48 0 180)
			(size 0.59 0.64)
			(layers "F.Cu" "F.Mask" "F.Paste")
			(roundrect_rratio 0.25)
			(net 363 "/X710-AT2 Misc/NCSI.TXD_0")
			(pintype "passive")
		)
		(pad "2" smd roundrect
			(at 0.48 0 180)
			(size 0.59 0.64)
			(layers "F.Cu" "F.Mask" "F.Paste")
			(roundrect_rratio 0.25)
			(net 7 "+3V3")
			(pintype "passive")
		)
	)
	(footprint "antmicro-footprints:C_0402_1005Metric"
		(layer "F.Cu")
		(at 109.35 93.45 90)
		(descr "Capacitor SMD 0402")
		(tags "capacitor SMD 0402")
		(property "Reference" "C215"
			(at 3.85 0.3 90)
			(layer "F.SilkS")
			(effects
				(font
					(size 0.7 0.7)
					(thickness 0.15)
				)
				(justify left bottom)
			)
		)
		(property "Value" "C_10p_0402"
			(at -1.022927 2.155213 90)
			(layer "F.Fab")
			(hide yes)
			(effects
				(font
					(size 0.7 0.7)
					(thickness 0.15)
				)
				(justify left bottom)
			)
		)
		(property "Datasheet" "https://www.murata.com/products/productdetail?partno=GCM1555C1H100GA16%23"
			(at 0 0 90)
			(layer "F.Fab")
			(hide yes)
			(effects
				(font
					(size 1.27 1.27)
					(thickness 0.15)
				)
			)
		)
		(property "Description" "SMD Multilayer Ceramic Capacitor, 10 pF, 50 V, 0402 [1005 Metric], ± 2%, C0G / NP0, GCM"
			(at 0 0 90)
			(layer "F.Fab")
			(hide yes)
			(effects
				(font
					(size 1.27 1.27)
					(thickness 0.15)
				)
			)
		)
		(property "MPN" "GCM1555C1H100GA16D"
			(at 0 0 90)
			(unlocked yes)
			(layer "F.Fab")
			(hide yes)
			(effects
				(font
					(size 1 1)
					(thickness 0.15)
				)
			)
		)
		(property "Manufacturer" "Murata"
			(at 0 0 90)
			(unlocked yes)
			(layer "F.Fab")
			(hide yes)
			(effects
				(font
					(size 1 1)
					(thickness 0.15)
				)
			)
		)
		(property "License" "Apache-2.0"
			(at 0 0 90)
			(unlocked yes)
			(layer "F.Fab")
			(hide yes)
			(effects
				(font
					(size 1 1)
					(thickness 0.15)
				)
			)
		)
		(property "Author" "Antmicro"
			(at 0 0 90)
			(unlocked yes)
			(layer "F.Fab")
			(hide yes)
			(effects
				(font
					(size 1 1)
					(thickness 0.15)
				)
			)
		)
		(property "Val" "10p"
			(at 0 0 90)
			(unlocked yes)
			(layer "F.Fab")
			(hide yes)
			(effects
				(font
					(size 1 1)
					(thickness 0.15)
				)
			)
		)
		(property "Voltage" "50V"
			(at 0 0 90)
			(unlocked yes)
			(layer "F.Fab")
			(hide yes)
			(effects
				(font
					(size 1 1)
					(thickness 0.15)
				)
			)
		)
		(property "Dielectric" "C0G"
			(at 0 0 90)
			(unlocked yes)
			(layer "F.Fab")
			(hide yes)
			(effects
				(font
					(size 1 1)
					(thickness 0.15)
				)
			)
		)
		(sheetname "/X710-AT2 10GbE/")
		(sheetfile "x710-at2-10gbe.kicad_sch")
		(attr smd)
		(fp_rect
			(start -0.925 -0.47)
			(end 0.925 0.47)
			(stroke
				(width 0.05)
				(type default)
			)
			(fill no)
			(layer "F.CrtYd")
		)
		(fp_line
			(start 0.504 -0.25)
			(end 0.504 0.248)
			(stroke
				(width 0.15)
				(type solid)
			)
			(layer "F.Fab")
		)
		(fp_line
			(start -0.494 -0.25)
			(end 0.504 -0.25)
			(stroke
				(width 0.15)
				(type solid)
			)
			(layer "F.Fab")
		)
		(fp_line
			(start 0.504 0.248)
			(end -0.494 0.248)
			(stroke
				(width 0.15)
				(type solid)
			)
			(layer "F.Fab")
		)
		(fp_line
			(start -0.494 0.248)
			(end -0.494 -0.25)
			(stroke
				(width 0.15)
				(type solid)
			)
			(layer "F.Fab")
		)
		(fp_text user "License: Apache-2.0"
			(at -0.939 5.799 90)
			(layer "F.Fab")
			(effects
				(font
					(size 0.7 0.7)
					(thickness 0.15)
				)
				(justify left bottom)
			)
		)
		(fp_text user "Author: Antmicro"
			(at -0.939 3.399 90)
			(layer "F.Fab")
			(effects
				(font
					(size 0.7 0.7)
					(thickness 0.15)
				)
				(justify left bottom)
			)
		)
		(fp_text user "${REFERENCE}"
			(at -0.939 4.599 90)
			(layer "F.Fab")
			(effects
				(font
					(size 0.7 0.7)
					(thickness 0.15)
				)
				(justify left bottom)
			)
		)
		(pad "1" smd roundrect
			(at -0.48 0 90)
			(size 0.59 0.64)
			(layers "F.Cu" "F.Mask" "F.Paste")
			(roundrect_rratio 0.25)
			(net 28 "GND")
			(pintype "passive")
		)
		(pad "2" smd roundrect
			(at 0.48 0 90)
			(size 0.59 0.64)
			(layers "F.Cu" "F.Mask" "F.Paste")
			(roundrect_rratio 0.25)
			(net 215 "/X710-AT2 10GbE/MDIO0_I2C0.MDIO")
			(pintype "passive")
		)
	)
	(footprint "antmicro-footprints:R_0402_1005Metric"
		(layer "F.Cu")
		(at 97.4 107.1 180)
		(descr "Resistor SMD 0402")
		(tags "resistor SMD 0402")
		(property "Reference" "R109"
			(at 2.25 -15.55 0)
			(layer "F.SilkS")
			(effects
				(font
					(size 0.7 0.7)
					(thickness 0.15)
				)
				(justify left bottom)
			)
		)
		(property "Value" "R_100R_0402"
			(at -1.011843 1.772046 0)
			(layer "F.Fab")
			(hide yes)
			(effects
				(font
					(size 0.7 0.7)
					(thickness 0.15)
				)
				(justify right top)
			)
		)
		(property "Datasheet" "https://www.bourns.com/docs/product-datasheets/cr.pdf"
			(at 0 0 0)
			(layer "F.Fab")
			(hide yes)
			(effects
				(font
					(size 1.27 1.27)
					(thickness 0.15)
				)
			)
		)
		(property "Description" "SMD Chip Resistor, 100 ohm, ± 1%, 62.5 mW, 0402 [1005 Metric], Thick Film, General Purpose"
			(at 0 0 0)
			(layer "F.Fab")
			(hide yes)
			(effects
				(font
					(size 1.27 1.27)
					(thickness 0.15)
				)
			)
		)
		(property "MPN" "CR0402-FX-1000GLF"
			(at 0 0 180)
			(unlocked yes)
			(layer "F.Fab")
			(hide yes)
			(effects
				(font
					(size 1 1)
					(thickness 0.15)
				)
			)
		)
		(property "Manufacturer" "Bourns"
			(at 0 0 180)
			(unlocked yes)
			(layer "F.Fab")
			(hide yes)
			(effects
				(font
					(size 1 1)
					(thickness 0.15)
				)
			)
		)
		(property "License" "Apache-2.0"
			(at 0 0 180)
			(unlocked yes)
			(layer "F.Fab")
			(hide yes)
			(effects
				(font
					(size 1 1)
					(thickness 0.15)
				)
			)
		)
		(property "Author" "Antmicro"
			(at 0 0 180)
			(unlocked yes)
			(layer "F.Fab")
			(hide yes)
			(effects
				(font
					(size 1 1)
					(thickness 0.15)
				)
			)
		)
		(property "Val" "100R"
			(at 0 0 180)
			(unlocked yes)
			(layer "F.Fab")
			(hide yes)
			(effects
				(font
					(size 1 1)
					(thickness 0.15)
				)
			)
		)
		(property "Tolerance" "1%"
			(at 0 0 180)
			(unlocked yes)
			(layer "F.Fab")
			(hide yes)
			(effects
				(font
					(size 1 1)
					(thickness 0.15)
				)
			)
		)
		(sheetname "/X710-AT2 Misc/")
		(sheetfile "x710-at2-mics.kicad_sch")
		(attr smd exclude_from_pos_files exclude_from_bom dnp)
		(fp_rect
			(start -0.925 -0.47)
			(end 0.925 0.47)
			(stroke
				(width 0.05)
				(type default)
			)
			(fill no)
			(layer "F.CrtYd")
		)
		(fp_rect
			(start -0.5 -0.25)
			(end 0.5 0.25)
			(stroke
				(width 0.15)
				(type solid)
			)
			(fill no)
			(layer "F.Fab")
		)
		(pad "1" smd roundrect
			(at -0.48 0 180)
			(size 0.59 0.64)
			(layers "F.Cu" "F.Mask" "F.Paste")
			(roundrect_rratio 0.25)
			(net 28 "GND")
			(pintype "passive")
		)
		(pad "2" smd roundrect
			(at 0.48 0 180)
			(size 0.59 0.64)
			(layers "F.Cu" "F.Mask" "F.Paste")
			(roundrect_rratio 0.25)
			(net 290 "/X710-AT2 Misc/~{DEV_DIS}")
			(pintype "passive")
		)
	)
	(footprint "antmicro-footprints:C_0603_1608Metric_EIA"
		(layer "F.Cu")
		(at 60.649999 93.150001)
		(descr "Capacitor SMD 0603, IPC-7351 Density Level A")
		(tags "Capacitor 0603")
		(property "Reference" "C45"
			(at -3.319999 -1.130001 0)
			(layer "F.SilkS")
			(effects
				(font
					(size 0.7 0.7)
					(thickness 0.15)
				)
				(justify left bottom)
			)
		)
		(property "Value" "C_22u_16V_0603"
			(at -1.42757 1.770288 0)
			(layer "F.Fab")
			(hide yes)
			(effects
				(font
					(size 0.7 0.7)
					(thickness 0.15)
				)
				(justify left bottom)
			)
		)
		(property "Datasheet" "https://product.samsungsem.com/mlcc/CL10A226MO7JZN.do"
			(at 0 0 0)
			(layer "F.Fab")
			(hide yes)
			(effects
				(font
					(size 1.27 1.27)
					(thickness 0.15)
				)
			)
		)
		(property "Description" "SMD Multilayer Ceramic Capacitor"
			(at 0 0 0)
			(layer "F.Fab")
			(hide yes)
			(effects
				(font
					(size 1.27 1.27)
					(thickness 0.15)
				)
			)
		)
		(property "MPN" "CL10A226MO7JZNC"
			(at 0 0 0)
			(unlocked yes)
			(layer "F.Fab")
			(hide yes)
			(effects
				(font
					(size 1 1)
					(thickness 0.15)
				)
			)
		)
		(property "Manufacturer" "Samsung Electro-Mechanics"
			(at 0 0 0)
			(unlocked yes)
			(layer "F.Fab")
			(hide yes)
			(effects
				(font
					(size 1 1)
					(thickness 0.15)
				)
			)
		)
		(property "License" "Apache-2.0"
			(at 0 0 0)
			(unlocked yes)
			(layer "F.Fab")
			(hide yes)
			(effects
				(font
					(size 1 1)
					(thickness 0.15)
				)
			)
		)
		(property "Author" "Antmicro"
			(at 0 0 0)
			(unlocked yes)
			(layer "F.Fab")
			(hide yes)
			(effects
				(font
					(size 1 1)
					(thickness 0.15)
				)
			)
		)
		(property "Val" "22u"
			(at 0 0 0)
			(unlocked yes)
			(layer "F.Fab")
			(hide yes)
			(effects
				(font
					(size 1 1)
					(thickness 0.15)
				)
			)
		)
		(property "Voltage" "16V"
			(at 0 0 0)
			(unlocked yes)
			(layer "F.Fab")
			(hide yes)
			(effects
				(font
					(size 1 1)
					(thickness 0.15)
				)
			)
		)
		(property "Dielectric" ""
			(at 0 0 0)
			(unlocked yes)
			(layer "F.Fab")
			(hide yes)
			(effects
				(font
					(size 1 1)
					(thickness 0.15)
				)
			)
		)
		(property "Public" "False"
			(at 0 0 0)
			(unlocked yes)
			(layer "F.Fab")
			(hide yes)
			(effects
				(font
					(size 1 1)
					(thickness 0.15)
				)
			)
		)
		(sheetname "/Power/")
		(sheetfile "power.kicad_sch")
		(attr smd)
		(fp_line
			(start -0.15 -0.55)
			(end 0.15 -0.55)
			(stroke
				(width 0.15)
				(type solid)
			)
			(layer "F.SilkS")
		)
		(fp_line
			(start -0.15 0.55)
			(end 0.15 0.55)
			(stroke
				(width 0.15)
				(type solid)
			)
			(layer "F.SilkS")
		)
		(fp_rect
			(start -1.25 -0.65)
			(end 1.25 0.65)
			(stroke
				(width 0.05)
				(type solid)
			)
			(fill no)
			(layer "F.CrtYd")
		)
		(fp_rect
			(start -0.8 -0.45)
			(end 0.8 0.45)
			(stroke
				(width 0.15)
				(type solid)
			)
			(fill no)
			(layer "F.Fab")
		)
		(pad "1" smd roundrect
			(at -0.7 0)
			(size 0.8 1.1)
			(layers "F.Cu" "F.Mask" "F.Paste")
			(roundrect_rratio 0.2)
			(net 28 "GND")
			(pintype "passive")
		)
		(pad "2" smd roundrect
			(at 0.7 0)
			(size 0.8 1.1)
			(layers "F.Cu" "F.Mask" "F.Paste")
			(roundrect_rratio 0.2)
			(net 311 "/Power/+DVDD_OUT")
			(pintype "passive")
		)
	)
)
